# T6G (Grand Teton) — schematic netlist excerpt (pin names and nets, part order shuffled) for the footprints in the layout excerpt that follows; sources: Cadence DE-HDL packaged netlist, KiCad conversion of 04192023_DAF0TMB3IC0_F0TG_MB_C_brd_V02_OCP.brd

R545  Q_RES  4.7K 5% CHIP  pkg 0402LF  page 55 : A = FM_BMC_READY_N ; B = PVDD18_S5_P1
C6624  Q_CAP_DIFFBUS  DIFF BUS_0.22UF 6.3V 20% X6S  pkg C0201  page 308 : \1\ = P5E_CPU0_P3_TX_BUF_C_DN<13> ; \2\ = P5E_CPU0_P3_TX_BUF_DN<13>
PC462  Q_CAP  0.1UF 25V 10% X7R  pkg 0402  page 193 : A = PVDDCR_CPU0_P0_VMON ; B = GND

(kicad_pcb
	(version 20260206)
	(generator "pcbnew")
	(generator_version "10.0")
	(general
		(thickness 1.6)
		(legacy_teardrops no)
	)
	(paper "A4")
	(title_block
		(title "04192023_DAF0TMB3IC0_F0TG_MB_C_brd_V02_OCP.brd")
		(comment 1 "Grand Teton / footprints 6800-6802 of 8354")
	)
	(layers
		(0 "F.Cu" signal "TOP")
		(4 "In1.Cu" signal "GND")
		(6 "In2.Cu" signal "IN1")
		(8 "In3.Cu" signal "GND1")
		(10 "In4.Cu" signal "IN2")
		(12 "In5.Cu" signal "GND2")
		(14 "In6.Cu" signal "IN3")
		(16 "In7.Cu" signal "GND3")
		(18 "In8.Cu" signal "VCC")
		(20 "In9.Cu" signal "VCC1")
		(22 "In10.Cu" signal "GND4")
		(24 "In11.Cu" signal "IN4")
		(26 "In12.Cu" signal "GND5")
		(28 "In13.Cu" signal "IN5")
		(30 "In14.Cu" signal "GND6")
		(32 "In15.Cu" signal "IN6")
		(34 "In16.Cu" signal "GND7")
		(2 "B.Cu" signal "BOTTOM")
		(9 "F.Adhes" user "F.Adhesive")
		(11 "B.Adhes" user "B.Adhesive")
		(13 "F.Paste" user "Package Geometry/Pastemask Top")
		(15 "B.Paste" user "Package Geometry/Pastemask Bottom")
		(5 "F.SilkS" user "Ref Des/Silkscreen Top")
		(7 "B.SilkS" user "Ref Des/Silkscreen Bottom")
		(1 "F.Mask" user "Board Geometry/Soldermask Top")
		(3 "B.Mask" user "Board Geometry/Soldermask Bottom")
		(17 "Dwgs.User" user "User.Drawings")
		(19 "Cmts.User" user "User.Comments")
		(21 "Eco1.User" user "User.Eco1")
		(23 "Eco2.User" user "User.Eco2")
		(25 "Edge.Cuts" user "Board Geometry/Outline")
		(27 "Margin" user)
		(31 "F.CrtYd" user "Package Geometry/Place Bound Top")
		(29 "B.CrtYd" user "Package Geometry/Place Bound Bottom")
		(35 "F.Fab" user "Ref Des/Assembly Top")
		(33 "B.Fab" user "Ref Des/Assembly Bottom")
	)
	(footprint ""
		(layer "B.Cu")
		(at 384.113278 -140.202158 180)
		(property "Reference" "PC462"
			(at 0 0 0)
			(layer "B.SilkS")
			(hide yes)
			(effects
				(font
					(size 1.27 1.27)
				)
				(justify mirror)
			)
		)
		(property "Value" ""
			(at 0 0 0)
			(layer "B.Fab")
			(effects
				(font
					(size 1.27 1.27)
				)
				(justify mirror)
			)
		)
		(duplicate_pad_numbers_are_jumpers no)
		(fp_line
			(start 0.7874 0.4064)
			(end 0.7874 -0.4064)
			(stroke
				(width 0.1524)
				(type default)
			)
			(layer "B.SilkS")
		)
		(fp_line
			(start 0.7874 -0.4064)
			(end -0.7874 -0.4064)
			(stroke
				(width 0.1524)
				(type default)
			)
			(layer "B.SilkS")
		)
		(fp_line
			(start -0.7874 0.4064)
			(end 0.7874 0.4064)
			(stroke
				(width 0.1524)
				(type default)
			)
			(layer "B.SilkS")
		)
		(fp_line
			(start -0.7874 -0.4064)
			(end -0.7874 0.4064)
			(stroke
				(width 0.1524)
				(type default)
			)
			(layer "B.SilkS")
		)
		(fp_line
			(start 0.67945 0.3048)
			(end 0.67945 -0.305054)
			(stroke
				(width 0.1)
				(type default)
			)
			(layer "B.Fab")
		)
		(fp_line
			(start 0.67945 -0.305054)
			(end 0.12065 -0.305054)
			(stroke
				(width 0.1)
				(type default)
			)
			(layer "B.Fab")
		)
		(fp_line
			(start 0.12065 0.3048)
			(end 0.67945 0.3048)
			(stroke
				(width 0.1)
				(type default)
			)
			(layer "B.Fab")
		)
		(fp_line
			(start 0.12065 0.2794)
			(end 0.12065 0.3048)
			(stroke
				(width 0.1)
				(type default)
			)
			(layer "B.Fab")
		)
		(fp_line
			(start 0.12065 -0.2794)
			(end -0.12065 -0.2794)
			(stroke
				(width 0.1)
				(type default)
			)
			(layer "B.Fab")
		)
		(fp_line
			(start 0.12065 -0.305054)
			(end 0.12065 -0.2794)
			(stroke
				(width 0.1)
				(type default)
			)
			(layer "B.Fab")
		)
		(fp_line
			(start -0.120396 0.3048)
			(end -0.120396 0.2794)
			(stroke
				(width 0.1)
				(type default)
			)
			(layer "B.Fab")
		)
		(fp_line
			(start -0.120396 0.2794)
			(end 0.12065 0.2794)
			(stroke
				(width 0.1)
				(type default)
			)
			(layer "B.Fab")
		)
		(fp_line
			(start -0.12065 -0.2794)
			(end -0.12065 -0.3048)
			(stroke
				(width 0.1)
				(type default)
			)
			(layer "B.Fab")
		)
		(fp_line
			(start -0.12065 -0.3048)
			(end -0.67945 -0.3048)
			(stroke
				(width 0.1)
				(type default)
			)
			(layer "B.Fab")
		)
		(fp_line
			(start -0.67945 0.3048)
			(end -0.120396 0.3048)
			(stroke
				(width 0.1)
				(type default)
			)
			(layer "B.Fab")
		)
		(fp_line
			(start -0.67945 -0.3048)
			(end -0.67945 0.3048)
			(stroke
				(width 0.1)
				(type default)
			)
			(layer "B.Fab")
		)
		(pad "1" smd circle
			(at 0.40005 0)
			(size 0 0)
			(layers "B.Cu" "B.Mask" "B.Paste")
			(net "PVDDCR_CPU0_P0_VMON")
		)
		(pad "2" smd circle
			(at -0.40005 0)
			(size 0 0)
			(layers "B.Cu" "B.Mask" "B.Paste")
			(net "GND")
		)
	)
	(footprint ""
		(layer "B.Cu")
		(at 94.488 -303.748948)
		(property "Reference" "R545"
			(at 0 0 0)
			(layer "B.SilkS")
			(hide yes)
			(effects
				(font
					(size 1.27 1.27)
				)
				(justify mirror)
			)
		)
		(property "Value" ""
			(at 0 0 0)
			(layer "B.Fab")
			(effects
				(font
					(size 1.27 1.27)
				)
				(justify mirror)
			)
		)
		(duplicate_pad_numbers_are_jumpers no)
		(fp_line
			(start -0.7874 -0.4064)
			(end -0.7874 0.4064)
			(stroke
				(width 0.1524)
				(type default)
			)
			(layer "B.SilkS")
		)
		(fp_line
			(start -0.7874 0.4064)
			(end 0.7874 0.4064)
			(stroke
				(width 0.1524)
				(type default)
			)
			(layer "B.SilkS")
		)
		(fp_line
			(start 0.7874 -0.4064)
			(end -0.7874 -0.4064)
			(stroke
				(width 0.1524)
				(type default)
			)
			(layer "B.SilkS")
		)
		(fp_line
			(start 0.7874 0.4064)
			(end 0.7874 -0.4064)
			(stroke
				(width 0.1524)
				(type default)
			)
			(layer "B.SilkS")
		)
		(fp_line
			(start -0.67945 -0.3048)
			(end -0.67945 0.3048)
			(stroke
				(width 0.1)
				(type default)
			)
			(layer "B.Fab")
		)
		(fp_line
			(start -0.67945 0.3048)
			(end -0.120396 0.3048)
			(stroke
				(width 0.1)
				(type default)
			)
			(layer "B.Fab")
		)
		(fp_line
			(start -0.12065 -0.3048)
			(end -0.67945 -0.3048)
			(stroke
				(width 0.1)
				(type default)
			)
			(layer "B.Fab")
		)
		(fp_line
			(start -0.12065 -0.2794)
			(end -0.12065 -0.3048)
			(stroke
				(width 0.1)
				(type default)
			)
			(layer "B.Fab")
		)
		(fp_line
			(start -0.120396 0.2794)
			(end 0.12065 0.2794)
			(stroke
				(width 0.1)
				(type default)
			)
			(layer "B.Fab")
		)
		(fp_line
			(start -0.120396 0.3048)
			(end -0.120396 0.2794)
			(stroke
				(width 0.1)
				(type default)
			)
			(layer "B.Fab")
		)
		(fp_line
			(start 0.12065 -0.305054)
			(end 0.12065 -0.2794)
			(stroke
				(width 0.1)
				(type default)
			)
			(layer "B.Fab")
		)
		(fp_line
			(start 0.12065 -0.2794)
			(end -0.12065 -0.2794)
			(stroke
				(width 0.1)
				(type default)
			)
			(layer "B.Fab")
		)
		(fp_line
			(start 0.12065 0.2794)
			(end 0.12065 0.3048)
			(stroke
				(width 0.1)
				(type default)
			)
			(layer "B.Fab")
		)
		(fp_line
			(start 0.12065 0.3048)
			(end 0.67945 0.3048)
			(stroke
				(width 0.1)
				(type default)
			)
			(layer "B.Fab")
		)
		(fp_line
			(start 0.67945 -0.305054)
			(end 0.12065 -0.305054)
			(stroke
				(width 0.1)
				(type default)
			)
			(layer "B.Fab")
		)
		(fp_line
			(start 0.67945 0.3048)
			(end 0.67945 -0.305054)
			(stroke
				(width 0.1)
				(type default)
			)
			(layer "B.Fab")
		)
		(pad "1" smd circle
			(at 0.40005 0 180)
			(size 0 0)
			(layers "B.Cu" "B.Mask" "B.Paste")
			(net "FM_BMC_READY_N")
		)
		(pad "2" smd circle
			(at -0.40005 0 180)
			(size 0 0)
			(layers "B.Cu" "B.Mask" "B.Paste")
			(net "PVDD18_S5_P1")
		)
	)
	(footprint ""
		(layer "B.Cu")
		(at 412.222442 -416.899344 90)
		(property "Reference" "C6624"
			(at 0 0 90)
			(layer "B.SilkS")
			(hide yes)
			(effects
				(font
					(size 1.27 1.27)
				)
				(justify mirror)
			)
		)
		(property "Value" ""
			(at 0 0 90)
			(layer "B.Fab")
			(effects
				(font
					(size 1.27 1.27)
				)
				(justify mirror)
			)
		)
		(duplicate_pad_numbers_are_jumpers no)
		(fp_line
			(start 0.299974 -0.150114)
			(end -0.299974 -0.150114)
			(stroke
				(width 0.1)
				(type default)
			)
			(layer "B.Fab")
		)
		(fp_line
			(start -0.299974 -0.150114)
			(end -0.299974 0.150114)
			(stroke
				(width 0.1)
				(type default)
			)
			(layer "B.Fab")
		)
		(fp_line
			(start 0.299974 0.150114)
			(end 0.299974 -0.150114)
			(stroke
				(width 0.1)
				(type default)
			)
			(layer "B.Fab")
		)
		(fp_line
			(start -0.299974 0.150114)
			(end 0.299974 0.150114)
			(stroke
				(width 0.1)
				(type default)
			)
			(layer "B.Fab")
		)
		(pad "1" smd rect
			(at 0.2667 0 270)
			(size 0.3048 0.381)
			(layers "B.Cu" "B.Mask" "B.Paste")
			(net "P5E_CPU0_P3_TX_BUF_C_DN<13>")
		)
		(pad "2" smd rect
			(at -0.2667 0 270)
			(size 0.3048 0.381)
			(layers "B.Cu" "B.Mask" "B.Paste")
			(net "P5E_CPU0_P3_TX_BUF_DN<13>")
		)
	)
)
